# BASEBOARD_FAB2 (Tioga Pass) — schematic netlist excerpt (pin names and nets, part order shuffled) for the footprints in the layout excerpt that follows; sources: Cadence DE-HDL packaged netlist, KiCad conversion of Wiwynn_Tioga_Pass_MB.brd

U1D1  TTL1G126_A  74HC1G126 IC  pkg SOT  page 200
  OE  = FM_OC_DETECT_EN
  A  = IRQ_OC_DETECT_N
  Y  = FM_OC_DETECT_N

C2D11  CAP  10UF 4V 20% X6S  pkg 0603LF  page 76 : A = PVSA_CPU1 ; B = GND
F9B1  FUSE  IC  pkg SM  page 172 : A(0) = P12V ; B(0) = P12V_HDD_SATA

(kicad_pcb
	(version 20260206)
	(generator "pcbnew")
	(generator_version "10.0")
	(general
		(thickness 1.6)
		(legacy_teardrops no)
	)
	(paper "A4")
	(title_block
		(title "Wiwynn_Tioga_Pass_MB.brd")
		(comment 1 "Tioga Pass / footprints 471-473 of 4770")
	)
	(layers
		(0 "F.Cu" signal "TOP")
		(4 "In1.Cu" signal "L2GND")
		(6 "In2.Cu" signal "L3")
		(8 "In3.Cu" signal "L4GND")
		(10 "In4.Cu" signal "L5")
		(12 "In5.Cu" signal "L6GND")
		(14 "In6.Cu" signal "L7VCC")
		(16 "In7.Cu" signal "L8VCC")
		(18 "In8.Cu" signal "L9GND")
		(20 "In9.Cu" signal "L10")
		(22 "In10.Cu" signal "L11GND")
		(24 "In11.Cu" signal "L12")
		(26 "In12.Cu" signal "L13GND")
		(2 "B.Cu" signal "BOTTOM")
		(9 "F.Adhes" user "F.Adhesive")
		(11 "B.Adhes" user "B.Adhesive")
		(13 "F.Paste" user "Package Geometry/Pastemask Top")
		(15 "B.Paste" user "Package Geometry/Pastemask Bottom")
		(5 "F.SilkS" user "Ref Des/Silkscreen Top")
		(7 "B.SilkS" user "Ref Des/Silkscreen Bottom")
		(1 "F.Mask" user "Board Geometry/Soldermask Top")
		(3 "B.Mask" user "Board Geometry/Soldermask Bottom")
		(17 "Dwgs.User" user "User.Drawings")
		(19 "Cmts.User" user "User.Comments")
		(21 "Eco1.User" user "User.Eco1")
		(23 "Eco2.User" user "User.Eco2")
		(25 "Edge.Cuts" user "Board Geometry/Outline")
		(27 "Margin" user)
		(31 "F.CrtYd" user "Package Geometry/Place Bound Top")
		(29 "B.CrtYd" user "Package Geometry/Place Bound Bottom")
		(35 "F.Fab" user "Ref Des/Assembly Top")
		(33 "B.Fab" user "Ref Des/Assembly Bottom")
	)
	(footprint ""
		(layer "F.Cu")
		(at 454.29932 -128.25222 -90)
		(property "Reference" "F9B1"
			(at 0 0 270)
			(layer "F.SilkS")
			(hide yes)
			(effects
				(font
					(size 1.27 1.27)
				)
			)
		)
		(property "Value" ""
			(at 0 0 270)
			(layer "F.Fab")
			(effects
				(font
					(size 1.27 1.27)
				)
			)
		)
		(duplicate_pad_numbers_are_jumpers no)
		(fp_poly
			(pts
				(xy 1.7018 4.7117) (xy -1.7018 4.7117) (xy -1.7018 -0.0127) (xy 1.7018 -0.0127)
			)
			(stroke
				(width 0)
				(type default)
			)
			(fill no)
			(layer "F.CrtYd")
		)
		(fp_line
			(start -1.7018 4.7117)
			(end -1.7018 -0.0127)
			(stroke
				(width 0.1)
				(type default)
			)
			(layer "F.Fab")
		)
		(fp_line
			(start 1.7018 4.7117)
			(end -1.7018 4.7117)
			(stroke
				(width 0.1)
				(type default)
			)
			(layer "F.Fab")
		)
		(fp_line
			(start -1.7018 -0.0127)
			(end 1.7018 -0.0127)
			(stroke
				(width 0.1)
				(type default)
			)
			(layer "F.Fab")
		)
		(fp_line
			(start 1.7018 -0.0127)
			(end 1.7018 4.7117)
			(stroke
				(width 0.1)
				(type default)
			)
			(layer "F.Fab")
		)
		(pad "1" smd rect
			(at 0 0 270)
			(size 3.302 1.397)
			(layers "F.Cu" "F.Mask" "F.Paste")
			(net "P12V")
		)
		(pad "2" smd rect
			(at 0 4.699 270)
			(size 3.302 1.397)
			(layers "F.Cu" "F.Mask" "F.Paste")
			(net "P12V_HDD_SATA")
		)
		(zone
			(layers "F.Cu" "B.Cu" "In1.Cu" "In2.Cu" "In3.Cu" "In4.Cu" "In5.Cu" "In6.Cu"
				"In7.Cu" "In8.Cu" "In9.Cu" "In10.Cu" "In11.Cu" "In12.Cu"
			)
			(hatch none 0.5)
			(connect_pads
				(clearance 0)
			)
			(min_thickness 0.25)
			(keepout
				(tracks allowed)
				(vias not_allowed)
				(pads allowed)
				(copperpour not_allowed)
				(footprints allowed)
			)
			(placement
				(enabled no)
				(sheetname "")
			)
			(fill
				(thermal_gap 0.5)
				(thermal_bridge_width 0.5)
				(island_removal_mode 0)
			)
			(polygon
				(pts
					(xy 450.29882 -129.90322) (xy 450.29882 -126.60122) (xy 453.60082 -126.60122) (xy 453.60082 -129.90322)
				)
			)
		)
	)
	(footprint ""
		(layer "F.Cu")
		(at 24.7015 -84.455)
		(property "Reference" "U1D1"
			(at -0.3683 -2.25933 0)
			(unlocked yes)
			(layer "F.SilkS")
			(effects
				(font
					(size 0.7874 0.5842)
					(thickness 0.1524)
				)
				(justify left)
			)
		)
		(property "Value" ""
			(at 0 0 0)
			(layer "F.Fab")
			(effects
				(font
					(size 1.27 1.27)
				)
			)
		)
		(duplicate_pad_numbers_are_jumpers no)
		(fp_circle
			(center -0.160782 -0.675386)
			(end -0.033782 -0.675386)
			(stroke
				(width 0.254)
				(type default)
			)
			(fill no)
			(layer "F.SilkS")
		)
		(fp_poly
			(pts
				(xy 0.21463 -0.450088) (xy 1.56337 -0.450088) (xy 1.56337 1.75006) (xy 0.21463 1.75006)
			)
			(stroke
				(width 0)
				(type default)
			)
			(fill no)
			(layer "F.CrtYd")
		)
		(fp_line
			(start 0.21463 -0.450088)
			(end 1.56337 -0.450088)
			(stroke
				(width 0.1)
				(type default)
			)
			(layer "F.Fab")
		)
		(fp_line
			(start 0.21463 1.75006)
			(end 0.21463 -0.450088)
			(stroke
				(width 0.1)
				(type default)
			)
			(layer "F.Fab")
		)
		(fp_line
			(start 1.56337 -0.450088)
			(end 1.56337 1.75006)
			(stroke
				(width 0.1)
				(type default)
			)
			(layer "F.Fab")
		)
		(fp_line
			(start 1.56337 1.75006)
			(end 0.21463 1.75006)
			(stroke
				(width 0.1)
				(type default)
			)
			(layer "F.Fab")
		)
		(fp_circle
			(center -0.4699 -0.8382)
			(end -0.3429 -0.8382)
			(stroke
				(width 0.254)
				(type default)
			)
			(fill no)
			(layer "F.Fab")
		)
		(pad "1" smd rect
			(at 0 0)
			(size 1.016 0.381)
			(layers "F.Cu" "F.Mask" "F.Paste")
			(net "FM_OC_DETECT_EN")
		)
		(pad "2" smd rect
			(at 0 0.649986)
			(size 1.016 0.381)
			(layers "F.Cu" "F.Mask" "F.Paste")
			(net "IRQ_OC_DETECT_N")
		)
		(pad "3" smd rect
			(at 0 1.299972)
			(size 1.016 0.381)
			(layers "F.Cu" "F.Mask" "F.Paste")
			(net "GND")
		)
		(pad "4" smd rect
			(at 1.778 1.299972)
			(size 1.016 0.381)
			(layers "F.Cu" "F.Mask" "F.Paste")
			(net "FM_OC_DETECT_N")
		)
		(pad "5" smd rect
			(at 1.778 0)
			(size 1.016 0.381)
			(layers "F.Cu" "F.Mask" "F.Paste")
			(net "P3V3_STBY")
		)
	)
	(footprint ""
		(layer "F.Cu")
		(at 95.69704 -81.573116)
		(property "Reference" "C2D11"
			(at 0 0 0)
			(layer "F.SilkS")
			(hide yes)
			(effects
				(font
					(size 1.27 1.27)
				)
			)
		)
		(property "Value" ""
			(at 0 0 0)
			(layer "F.Fab")
			(effects
				(font
					(size 1.27 1.27)
				)
			)
		)
		(duplicate_pad_numbers_are_jumpers no)
		(fp_poly
			(pts
				(xy -0.4953 -0.2032) (xy 0.4953 -0.2032) (xy 0.4953 1.6002) (xy -0.4953 1.6002)
			)
			(stroke
				(width 0)
				(type default)
			)
			(fill no)
			(layer "F.CrtYd")
		)
		(fp_line
			(start -0.4953 -0.2032)
			(end 0.4953 -0.2032)
			(stroke
				(width 0.1)
				(type default)
			)
			(layer "F.Fab")
		)
		(fp_line
			(start -0.4953 1.6002)
			(end -0.4953 -0.2032)
			(stroke
				(width 0.1)
				(type default)
			)
			(layer "F.Fab")
		)
		(fp_line
			(start 0.4953 -0.2032)
			(end 0.4953 1.6002)
			(stroke
				(width 0.1)
				(type default)
			)
			(layer "F.Fab")
		)
		(fp_line
			(start 0.4953 1.6002)
			(end -0.4953 1.6002)
			(stroke
				(width 0.1)
				(type default)
			)
			(layer "F.Fab")
		)
		(pad "1" smd rect
			(at 0 0)
			(size 0.762 0.889)
			(layers "F.Cu" "F.Mask" "F.Paste")
			(net "PVSA_CPU1")
		)
		(pad "2" smd rect
			(at 0 1.397)
			(size 0.762 0.889)
			(layers "F.Cu" "F.Mask" "F.Paste")
			(net "GND")
		)
		(zone
			(layer "F.Cu")
			(hatch none 0.5)
			(connect_pads
				(clearance 0)
			)
			(min_thickness 0.25)
			(keepout
				(tracks not_allowed)
				(vias allowed)
				(pads allowed)
				(copperpour not_allowed)
				(footprints allowed)
			)
			(placement
				(enabled no)
				(sheetname "")
			)
			(fill
				(thermal_gap 0.5)
				(thermal_bridge_width 0.5)
				(island_removal_mode 0)
			)
			(polygon
				(pts
					(xy 95.31604 -81.128616) (xy 96.07804 -81.128616) (xy 96.07804 -80.620616) (xy 95.31604 -80.620616)
				)
			)
		)
	)
)
